# SCM (Grand Teton) — schematic netlist excerpt (pin names and nets, part order shuffled) for the footprints in the layout excerpt that follows; sources: Cadence DE-HDL packaged netlist, KiCad conversion of 12092022_DA0F0TMDCD0_F0T_Management_Board_D_brd_V3_OCP.brd

R355  Q_RES  120 1% CHIP  pkg 0402LF  page 20 : A = M_BMC_DDR4_MA<4> ; B = P1V2_AUX
R532  Q_RES  33.2 1% EMPTY  pkg 0402LF  page 21 : A = EMMC_DT3_R ; B = BMC_EMMC_DT3

(kicad_pcb
	(version 20260206)
	(generator "pcbnew")
	(generator_version "10.0")
	(general
		(thickness 1.6)
		(legacy_teardrops no)
	)
	(paper "A4")
	(title_block
		(title "12092022_DA0F0TMDCD0_F0T_Management_Board_D_brd_V3_OCP.brd")
		(comment 1 "Grand Teton / footprints 543-544 of 1440")
	)
	(layers
		(0 "F.Cu" signal "TOP")
		(4 "In1.Cu" signal "GND")
		(6 "In2.Cu" signal "IN1")
		(8 "In3.Cu" signal "GND1")
		(10 "In4.Cu" signal "IN2")
		(12 "In5.Cu" signal "VCC")
		(14 "In6.Cu" signal "VCC1")
		(16 "In7.Cu" signal "IN3")
		(18 "In8.Cu" signal "GND2")
		(20 "In9.Cu" signal "IN4")
		(22 "In10.Cu" signal "GND3")
		(2 "B.Cu" signal "BOTTOM")
		(9 "F.Adhes" user "F.Adhesive")
		(11 "B.Adhes" user "B.Adhesive")
		(13 "F.Paste" user "Package Geometry/Pastemask Top")
		(15 "B.Paste" user "Package Geometry/Pastemask Bottom")
		(5 "F.SilkS" user "Ref Des/Silkscreen Top")
		(7 "B.SilkS" user "Ref Des/Silkscreen Bottom")
		(1 "F.Mask" user "Board Geometry/Soldermask Top")
		(3 "B.Mask" user "Board Geometry/Soldermask Bottom")
		(17 "Dwgs.User" user "User.Drawings")
		(19 "Cmts.User" user "User.Comments")
		(21 "Eco1.User" user "User.Eco1")
		(23 "Eco2.User" user "User.Eco2")
		(25 "Edge.Cuts" user "Board Geometry/Outline")
		(27 "Margin" user)
		(31 "F.CrtYd" user "Package Geometry/Place Bound Top")
		(29 "B.CrtYd" user "Package Geometry/Place Bound Bottom")
		(35 "F.Fab" user "Ref Des/Assembly Top")
		(33 "B.Fab" user "Ref Des/Assembly Bottom")
	)
	(footprint ""
		(layer "F.Cu")
		(at 77.707744 -37.559488 -90)
		(property "Reference" "R355"
			(at 0 0 270)
			(layer "F.SilkS")
			(hide yes)
			(effects
				(font
					(size 1.27 1.27)
				)
			)
		)
		(property "Value" ""
			(at 0 0 270)
			(layer "F.Fab")
			(effects
				(font
					(size 1.27 1.27)
				)
			)
		)
		(duplicate_pad_numbers_are_jumpers no)
		(fp_line
			(start -0.7874 0.4064)
			(end -0.7874 -0.4064)
			(stroke
				(width 0.1524)
				(type default)
			)
			(layer "F.SilkS")
		)
		(fp_line
			(start 0.7874 0.4064)
			(end -0.7874 0.4064)
			(stroke
				(width 0.1524)
				(type default)
			)
			(layer "F.SilkS")
		)
		(fp_line
			(start -0.7874 -0.4064)
			(end 0.7874 -0.4064)
			(stroke
				(width 0.1524)
				(type default)
			)
			(layer "F.SilkS")
		)
		(fp_line
			(start 0.7874 -0.4064)
			(end 0.7874 0.4064)
			(stroke
				(width 0.1524)
				(type default)
			)
			(layer "F.SilkS")
		)
		(fp_line
			(start -0.67945 0.3048)
			(end -0.67945 -0.305054)
			(stroke
				(width 0.1)
				(type default)
			)
			(layer "F.Fab")
		)
		(fp_line
			(start -0.12065 0.3048)
			(end -0.67945 0.3048)
			(stroke
				(width 0.1)
				(type default)
			)
			(layer "F.Fab")
		)
		(fp_line
			(start 0.120396 0.3048)
			(end 0.120396 0.2794)
			(stroke
				(width 0.1)
				(type default)
			)
			(layer "F.Fab")
		)
		(fp_line
			(start 0.67945 0.3048)
			(end 0.120396 0.3048)
			(stroke
				(width 0.1)
				(type default)
			)
			(layer "F.Fab")
		)
		(fp_line
			(start -0.12065 0.2794)
			(end -0.12065 0.3048)
			(stroke
				(width 0.1)
				(type default)
			)
			(layer "F.Fab")
		)
		(fp_line
			(start 0.120396 0.2794)
			(end -0.12065 0.2794)
			(stroke
				(width 0.1)
				(type default)
			)
			(layer "F.Fab")
		)
		(fp_line
			(start -0.12065 -0.2794)
			(end 0.12065 -0.2794)
			(stroke
				(width 0.1)
				(type default)
			)
			(layer "F.Fab")
		)
		(fp_line
			(start 0.12065 -0.2794)
			(end 0.12065 -0.3048)
			(stroke
				(width 0.1)
				(type default)
			)
			(layer "F.Fab")
		)
		(fp_line
			(start 0.12065 -0.3048)
			(end 0.67945 -0.3048)
			(stroke
				(width 0.1)
				(type default)
			)
			(layer "F.Fab")
		)
		(fp_line
			(start 0.67945 -0.3048)
			(end 0.67945 0.3048)
			(stroke
				(width 0.1)
				(type default)
			)
			(layer "F.Fab")
		)
		(fp_line
			(start -0.67945 -0.305054)
			(end -0.12065 -0.305054)
			(stroke
				(width 0.1)
				(type default)
			)
			(layer "F.Fab")
		)
		(fp_line
			(start -0.12065 -0.305054)
			(end -0.12065 -0.2794)
			(stroke
				(width 0.1)
				(type default)
			)
			(layer "F.Fab")
		)
		(pad "1" smd circle
			(at -0.40005 0 270)
			(size 0 0)
			(layers "F.Cu" "F.Mask" "F.Paste")
			(net "M_BMC_DDR4_MA<4>")
		)
		(pad "2" smd circle
			(at 0.40005 0 270)
			(size 0 0)
			(layers "F.Cu" "F.Mask" "F.Paste")
			(net "P1V2_AUX")
		)
	)
	(footprint ""
		(layer "F.Cu")
		(at 32.999172 -83.816952 90)
		(property "Reference" "R532"
			(at 0 0 90)
			(layer "F.SilkS")
			(hide yes)
			(effects
				(font
					(size 1.27 1.27)
				)
			)
		)
		(property "Value" ""
			(at 0 0 90)
			(layer "F.Fab")
			(effects
				(font
					(size 1.27 1.27)
				)
			)
		)
		(duplicate_pad_numbers_are_jumpers no)
		(fp_line
			(start 0.7874 -0.4064)
			(end 0.7874 0.4064)
			(stroke
				(width 0.1524)
				(type default)
			)
			(layer "F.SilkS")
		)
		(fp_line
			(start -0.7874 -0.4064)
			(end 0.7874 -0.4064)
			(stroke
				(width 0.1524)
				(type default)
			)
			(layer "F.SilkS")
		)
		(fp_line
			(start 0.7874 0.4064)
			(end -0.7874 0.4064)
			(stroke
				(width 0.1524)
				(type default)
			)
			(layer "F.SilkS")
		)
		(fp_line
			(start -0.7874 0.4064)
			(end -0.7874 -0.4064)
			(stroke
				(width 0.1524)
				(type default)
			)
			(layer "F.SilkS")
		)
		(fp_line
			(start -0.12065 -0.305054)
			(end -0.12065 -0.2794)
			(stroke
				(width 0.1)
				(type default)
			)
			(layer "F.Fab")
		)
		(fp_line
			(start -0.67945 -0.305054)
			(end -0.12065 -0.305054)
			(stroke
				(width 0.1)
				(type default)
			)
			(layer "F.Fab")
		)
		(fp_line
			(start 0.67945 -0.3048)
			(end 0.67945 0.3048)
			(stroke
				(width 0.1)
				(type default)
			)
			(layer "F.Fab")
		)
		(fp_line
			(start 0.12065 -0.3048)
			(end 0.67945 -0.3048)
			(stroke
				(width 0.1)
				(type default)
			)
			(layer "F.Fab")
		)
		(fp_line
			(start 0.12065 -0.2794)
			(end 0.12065 -0.3048)
			(stroke
				(width 0.1)
				(type default)
			)
			(layer "F.Fab")
		)
		(fp_line
			(start -0.12065 -0.2794)
			(end 0.12065 -0.2794)
			(stroke
				(width 0.1)
				(type default)
			)
			(layer "F.Fab")
		)
		(fp_line
			(start 0.120396 0.2794)
			(end -0.12065 0.2794)
			(stroke
				(width 0.1)
				(type default)
			)
			(layer "F.Fab")
		)
		(fp_line
			(start -0.12065 0.2794)
			(end -0.12065 0.3048)
			(stroke
				(width 0.1)
				(type default)
			)
			(layer "F.Fab")
		)
		(fp_line
			(start 0.67945 0.3048)
			(end 0.120396 0.3048)
			(stroke
				(width 0.1)
				(type default)
			)
			(layer "F.Fab")
		)
		(fp_line
			(start 0.120396 0.3048)
			(end 0.120396 0.2794)
			(stroke
				(width 0.1)
				(type default)
			)
			(layer "F.Fab")
		)
		(fp_line
			(start -0.12065 0.3048)
			(end -0.67945 0.3048)
			(stroke
				(width 0.1)
				(type default)
			)
			(layer "F.Fab")
		)
		(fp_line
			(start -0.67945 0.3048)
			(end -0.67945 -0.305054)
			(stroke
				(width 0.1)
				(type default)
			)
			(layer "F.Fab")
		)
		(pad "1" smd circle
			(at -0.40005 0 90)
			(size 0 0)
			(layers "F.Cu" "F.Mask" "F.Paste")
			(net "EMMC_DT3_R")
		)
		(pad "2" smd circle
			(at 0.40005 0 90)
			(size 0 0)
			(layers "F.Cu" "F.Mask" "F.Paste")
			(net "BMC_EMMC_DT3")
		)
	)
)
